(kicad_pcb
	(version 20260206)
	(generator "pcbnew")
	(generator_version "10.0")
	(general
		(thickness 1.6)
		(legacy_teardrops no)
	)
	(paper "A4")
	(title_block
		(title "Bryce Canyon_F.DPB_16315-1-OCP.brd")
		(comment 1 "Bryce Canyon / footprints 1046-1052 of 2223")
	)
	(layers
		(0 "F.Cu" signal "TOP")
		(4 "In1.Cu" signal "L2GND")
		(6 "In2.Cu" signal "L3")
		(8 "In3.Cu" signal "L4GND")
		(10 "In4.Cu" signal "L5")
		(12 "In5.Cu" signal "L6VCC")
		(14 "In6.Cu" signal "L7VCC")
		(16 "In7.Cu" signal "L8")
		(18 "In8.Cu" signal "L9GND")
		(20 "In9.Cu" signal "L10")
		(22 "In10.Cu" signal "L11GND")
		(2 "B.Cu" signal "BOTTOM")
		(9 "F.Adhes" user "F.Adhesive")
		(11 "B.Adhes" user "B.Adhesive")
		(13 "F.Paste" user "Package Geometry/Pastemask Top")
		(15 "B.Paste" user "Package Geometry/Pastemask Bottom")
		(5 "F.SilkS" user "Ref Des/Silkscreen Top")
		(7 "B.SilkS" user "Ref Des/Silkscreen Bottom")
		(1 "F.Mask" user "Board Geometry/Soldermask Top")
		(3 "B.Mask" user "Board Geometry/Soldermask Bottom")
		(17 "Dwgs.User" user "User.Drawings")
		(19 "Cmts.User" user "User.Comments")
		(21 "Eco1.User" user "User.Eco1")
		(23 "Eco2.User" user "User.Eco2")
		(25 "Edge.Cuts" user "Board Geometry/Outline")
		(27 "Margin" user)
		(31 "F.CrtYd" user "Package Geometry/Place Bound Top")
		(29 "B.CrtYd" user "Package Geometry/Place Bound Bottom")
		(35 "F.Fab" user "Ref Des/Assembly Top")
		(33 "B.Fab" user "Ref Des/Assembly Bottom")
	)
	(footprint ""
		(layer "F.Cu")
		(at 143.999966 -324.39991)
		(property "Reference" "RLED29"
			(at 0 0 0)
			(layer "F.SilkS")
			(hide yes)
			(effects
				(font
					(size 1.27 1.27)
				)
			)
		)
		(property "Value" "LED-BY-19-GP"
			(at -2.132076 1.414018 0)
			(unlocked yes)
			(layer "F.Fab")
			(hide yes)
			(effects
				(font
					(size 1.016 1.016)
					(thickness 0.1524)
				)
			)
		)
		(property "Device Type" "LED-1615-4PH26"
			(at -2.132076 -0.109982 0)
			(unlocked yes)
			(layer "F.Fab")
			(hide yes)
			(effects
				(font
					(size 1.016 1.016)
					(thickness 0.1524)
				)
			)
		)
		(duplicate_pad_numbers_are_jumpers no)
		(fp_line
			(start -1.2954 0.254)
			(end -1.2954 1.6002)
			(stroke
				(width 0.508)
				(type default)
			)
			(layer "F.SilkS")
		)
		(fp_line
			(start -1.2954 1.6002)
			(end 1.2954 1.6002)
			(stroke
				(width 0.508)
				(type default)
			)
			(layer "F.SilkS")
		)
		(fp_line
			(start -1.1176 -1.4224)
			(end 1.1176 -1.4224)
			(stroke
				(width 0.1524)
				(type default)
			)
			(layer "F.SilkS")
		)
		(fp_line
			(start -1.1176 1.4224)
			(end -1.1176 -1.4224)
			(stroke
				(width 0.1524)
				(type default)
			)
			(layer "F.SilkS")
		)
		(fp_line
			(start 1.1176 -1.4224)
			(end 1.1176 1.4224)
			(stroke
				(width 0.1524)
				(type default)
			)
			(layer "F.SilkS")
		)
		(fp_line
			(start 1.1176 1.4224)
			(end -1.1176 1.4224)
			(stroke
				(width 0.1524)
				(type default)
			)
			(layer "F.SilkS")
		)
		(fp_line
			(start 1.2954 1.6002)
			(end 1.2954 0.254)
			(stroke
				(width 0.508)
				(type default)
			)
			(layer "F.SilkS")
		)
		(fp_rect
			(start -0.7493 0.8001)
			(end 0.7493 -0.8001)
			(stroke
				(width 0)
				(type default)
			)
			(fill no)
			(layer "F.CrtYd")
		)
		(fp_poly
			(pts
				(xy -1.3716 1.6764) (xy -1.3716 -1.6764) (xy 1.3716 -1.6764) (xy 1.3716 0.0635) (xy 0.7493 0.0635)
				(xy 0.7493 -0.8001) (xy -0.7493 -0.8001) (xy -0.7493 0.8001) (xy 0.7493 0.8001) (xy 0.7493 0.0762)
				(xy 1.3716 0.0762) (xy 1.3716 1.6764)
			)
			(stroke
				(width 0)
				(type default)
			)
			(fill no)
			(layer "F.CrtYd")
		)
		(fp_rect
			(start -1.3716 1.6764)
			(end 1.3716 -1.6764)
			(stroke
				(width 0)
				(type default)
			)
			(fill no)
			(layer "F.Fab")
		)
		(pad "1" smd rect
			(at 0.50038 -0.73025)
			(size 0.7112 0.8636)
			(layers "F.Cu" "F.Mask" "F.Paste")
			(net "DRV_ACT_28")
		)
		(pad "2" smd rect
			(at -0.50038 -0.73025)
			(size 0.7112 0.8636)
			(layers "F.Cu" "F.Mask" "F.Paste")
			(net "FLT_HDD28")
		)
		(pad "3" smd rect
			(at 0.50038 0.73025)
			(size 0.7112 0.8636)
			(layers "F.Cu" "F.Mask" "F.Paste")
			(net "DRV_ACT_28_N")
		)
		(pad "4" smd rect
			(at -0.50038 0.73025)
			(size 0.7112 0.8636)
			(layers "F.Cu" "F.Mask" "F.Paste")
			(net "FLT_HDD28_N")
		)
	)
	(footprint ""
		(layer "F.Cu")
		(at 6.812788 -172.385482)
		(property "Reference" "Q263"
			(at 0 0 0)
			(layer "F.SilkS")
			(hide yes)
			(effects
				(font
					(size 1.27 1.27)
				)
			)
		)
		(property "Value" "SSM3K324R-GP"
			(at 0.127 -8.9662 0)
			(unlocked yes)
			(layer "F.Fab")
			(hide yes)
			(effects
				(font
					(size 1.016 1.016)
					(thickness 0.1524)
				)
			)
		)
		(property "Device Type" "SOT23DGS2D4H35"
			(at 0.127 -10.4902 0)
			(unlocked yes)
			(layer "F.Fab")
			(hide yes)
			(effects
				(font
					(size 1.016 1.016)
					(thickness 0.1524)
				)
			)
		)
		(duplicate_pad_numbers_are_jumpers no)
		(fp_line
			(start -1.651 -1.778)
			(end -1.651 1.778)
			(stroke
				(width 0.1524)
				(type default)
			)
			(layer "F.SilkS")
		)
		(fp_line
			(start -1.651 1.778)
			(end 1.651 1.778)
			(stroke
				(width 0.1524)
				(type default)
			)
			(layer "F.SilkS")
		)
		(fp_line
			(start 1.651 -1.778)
			(end -1.651 -1.778)
			(stroke
				(width 0.1524)
				(type default)
			)
			(layer "F.SilkS")
		)
		(fp_line
			(start 1.651 1.778)
			(end 1.651 -1.778)
			(stroke
				(width 0.1524)
				(type default)
			)
			(layer "F.SilkS")
		)
		(fp_poly
			(pts
				(xy -1.778 1.8796) (xy -1.778 -1.8796) (xy 1.778 -1.8796) (xy 1.778 1.8796)
			)
			(stroke
				(width 0)
				(type default)
			)
			(fill no)
			(layer "F.CrtYd")
		)
		(fp_poly
			(pts
				(xy -1.778 1.8796) (xy -1.778 -1.8796) (xy 1.778 -1.8796) (xy 1.778 1.8796)
			)
			(stroke
				(width 0)
				(type default)
			)
			(fill no)
			(layer "F.Fab")
		)
		(pad "D" smd custom
			(at 0 -0.9525)
			(size 0.1905 0.1905)
			(layers "F.Cu" "F.Mask" "F.Paste")
			(net "DRV_ACT_0_N")
			(options
				(clearance outline)
				(anchor circle)
			)
			(primitives
				(gr_poly
					(pts
						(arc
							(start -0.1778 0.5715)
							(mid -0.321484 0.511984)
							(end -0.381 0.3683)
						)
						(arc
							(start -0.381 -0.3683)
							(mid -0.321484 -0.511984)
							(end -0.1778 -0.5715)
						)
						(arc
							(start 0.1778 -0.5715)
							(mid 0.321484 -0.511984)
							(end 0.381 -0.3683)
						)
						(arc
							(start 0.381 0.3683)
							(mid 0.321484 0.511984)
							(end 0.1778 0.5715)
						)
					)
					(width 0)
					(fill yes)
				)
			)
		)
		(pad "G" smd custom
			(at -0.98425 0.9525)
			(size 0.1905 0.1905)
			(layers "F.Cu" "F.Mask" "F.Paste")
			(net "DRIVE_A_0_ACT")
			(options
				(clearance outline)
				(anchor circle)
			)
			(primitives
				(gr_poly
					(pts
						(arc
							(start -0.1778 0.5715)
							(mid -0.321484 0.511984)
							(end -0.381 0.3683)
						)
						(arc
							(start -0.381 -0.3683)
							(mid -0.321484 -0.511984)
							(end -0.1778 -0.5715)
						)
						(arc
							(start 0.1778 -0.5715)
							(mid 0.321484 -0.511984)
							(end 0.381 -0.3683)
						)
						(arc
							(start 0.381 0.3683)
							(mid 0.321484 0.511984)
							(end 0.1778 0.5715)
						)
					)
					(width 0)
					(fill yes)
				)
			)
		)
		(pad "S" smd custom
			(at 0.98425 0.9525)
			(size 0.1905 0.1905)
			(layers "F.Cu" "F.Mask" "F.Paste")
			(net "GND")
			(options
				(clearance outline)
				(anchor circle)
			)
			(primitives
				(gr_poly
					(pts
						(arc
							(start -0.1778 0.5715)
							(mid -0.321484 0.511984)
							(end -0.381 0.3683)
						)
						(arc
							(start -0.381 -0.3683)
							(mid -0.321484 -0.511984)
							(end -0.1778 -0.5715)
						)
						(arc
							(start 0.1778 -0.5715)
							(mid 0.321484 -0.511984)
							(end 0.381 -0.3683)
						)
						(arc
							(start 0.381 0.3683)
							(mid 0.321484 0.511984)
							(end 0.1778 0.5715)
						)
					)
					(width 0)
					(fill yes)
				)
			)
		)
	)
	(footprint ""
		(layer "F.Cu")
		(at 70.313804 -294.191182 90)
		(property "Reference" "R557"
			(at 0 0 90)
			(layer "F.SilkS")
			(hide yes)
			(effects
				(font
					(size 1.27 1.27)
				)
			)
		)
		(property "Value" "4K7R2J-2-GP"
			(at 0.064008 -3.993896 90)
			(unlocked yes)
			(layer "F.Fab")
			(hide yes)
			(effects
				(font
					(size 1.016 1.016)
					(thickness 0.1524)
				)
			)
		)
		(property "Device Type" "R402H16"
			(at 0.064008 -5.517896 90)
			(unlocked yes)
			(layer "F.Fab")
			(hide yes)
			(effects
				(font
					(size 1.016 1.016)
					(thickness 0.1524)
				)
			)
		)
		(duplicate_pad_numbers_are_jumpers no)
		(fp_line
			(start 0.508 -0.9398)
			(end -0.508 -0.9398)
			(stroke
				(width 0.1524)
				(type default)
			)
			(layer "F.SilkS")
		)
		(fp_line
			(start -0.508 -0.9398)
			(end -0.508 0.9398)
			(stroke
				(width 0.1524)
				(type default)
			)
			(layer "F.SilkS")
		)
		(fp_rect
			(start -0.508 0.9398)
			(end 0.508 -0.9398)
			(stroke
				(width 0)
				(type default)
			)
			(fill no)
			(layer "F.CrtYd")
		)
		(fp_rect
			(start -0.508 0.9398)
			(end 0.508 -0.9398)
			(stroke
				(width 0)
				(type default)
			)
			(fill no)
			(layer "F.Fab")
		)
		(pad "1" smd custom
			(at 0 -0.4445 90)
			(size 0.1397 0.1397)
			(layers "F.Cu" "F.Mask" "F.Paste")
			(net "DRIVE_B_26_ACT")
			(options
				(clearance outline)
				(anchor circle)
			)
			(primitives
				(gr_poly
					(pts
						(arc
							(start -0.1778 -0.2794)
							(mid -0.249642 -0.249642)
							(end -0.2794 -0.1778)
						)
						(arc
							(start -0.2794 0.1778)
							(mid -0.249642 0.249642)
							(end -0.1778 0.2794)
						)
						(arc
							(start 0.1778 0.2794)
							(mid 0.249642 0.249642)
							(end 0.2794 0.1778)
						)
						(arc
							(start 0.2794 -0.1778)
							(mid 0.249642 -0.249642)
							(end 0.1778 -0.2794)
						)
					)
					(width 0)
					(fill yes)
				)
			)
		)
		(pad "2" smd custom
			(at 0 0.4445 90)
			(size 0.1397 0.1397)
			(layers "F.Cu" "F.Mask" "F.Paste")
			(net "GND")
			(options
				(clearance outline)
				(anchor circle)
			)
			(primitives
				(gr_poly
					(pts
						(arc
							(start -0.1778 -0.2794)
							(mid -0.249642 -0.249642)
							(end -0.2794 -0.1778)
						)
						(arc
							(start -0.2794 0.1778)
							(mid -0.249642 0.249642)
							(end -0.1778 0.2794)
						)
						(arc
							(start 0.1778 0.2794)
							(mid 0.249642 0.249642)
							(end 0.2794 0.1778)
						)
						(arc
							(start 0.2794 -0.1778)
							(mid 0.249642 -0.249642)
							(end 0.1778 -0.2794)
						)
					)
					(width 0)
					(fill yes)
				)
			)
		)
	)
	(footprint ""
		(layer "F.Cu")
		(at 190.213488 -273.660616 90)
		(property "Reference" "C104"
			(at 0 0 90)
			(layer "F.SilkS")
			(hide yes)
			(effects
				(font
					(size 1.27 1.27)
				)
			)
		)
		(property "Value" "SCD01U16V1KX-GP"
			(at -2.8321 -1.7399 90)
			(unlocked yes)
			(layer "F.Fab")
			(hide yes)
			(effects
				(font
					(size 1.016 1.016)
					(thickness 0.1524)
				)
			)
		)
		(property "Device Type" "C0201H13"
			(at -2.8321 -3.2639 90)
			(unlocked yes)
			(layer "F.Fab")
			(hide yes)
			(effects
				(font
					(size 1.016 1.016)
					(thickness 0.1524)
				)
			)
		)
		(duplicate_pad_numbers_are_jumpers no)
		(fp_rect
			(start -0.2794 0.6477)
			(end 0.2794 -0.6477)
			(stroke
				(width 0)
				(type default)
			)
			(fill no)
			(layer "F.CrtYd")
		)
		(fp_rect
			(start -0.2794 0.6477)
			(end 0.2794 -0.6477)
			(stroke
				(width 0)
				(type default)
			)
			(fill no)
			(layer "F.Fab")
		)
		(pad "1" smd custom
			(at 0 -0.2794 90)
			(size 0.0762 0.0762)
			(layers "F.Cu" "F.Mask" "F.Paste")
			(net "SAS_HDD_RX_P5")
			(options
				(clearance outline)
				(anchor circle)
			)
			(primitives
				(gr_poly
					(pts
						(arc
							(start 0.1524 -0.127)
							(mid 0.137521 -0.162921)
							(end 0.1016 -0.1778)
						)
						(arc
							(start -0.1016 -0.1778)
							(mid -0.137521 -0.162921)
							(end -0.1524 -0.127)
						)
						(arc
							(start -0.1524 0.127)
							(mid -0.137521 0.162921)
							(end -0.1016 0.1778)
						)
						(arc
							(start 0.1016 0.1778)
							(mid 0.137521 0.162921)
							(end 0.1524 0.127)
						)
					)
					(width 0)
					(fill yes)
				)
			)
		)
		(pad "2" smd custom
			(at 0 0.2794 90)
			(size 0.0762 0.0762)
			(layers "F.Cu" "F.Mask" "F.Paste")
			(net "PHY_SCC_A_TO_DRV_A_5_DP")
			(options
				(clearance outline)
				(anchor circle)
			)
			(primitives
				(gr_poly
					(pts
						(arc
							(start 0.1524 -0.127)
							(mid 0.137521 -0.162921)
							(end 0.1016 -0.1778)
						)
						(arc
							(start -0.1016 -0.1778)
							(mid -0.137521 -0.162921)
							(end -0.1524 -0.127)
						)
						(arc
							(start -0.1524 0.127)
							(mid -0.137521 0.162921)
							(end -0.1016 0.1778)
						)
						(arc
							(start 0.1016 0.1778)
							(mid 0.137521 0.162921)
							(end 0.1524 0.127)
						)
					)
					(width 0)
					(fill yes)
				)
			)
		)
	)
	(footprint ""
		(layer "F.Cu")
		(at 261.9756 -284.4292 180)
		(property "Reference" "R101"
			(at 0 0 180)
			(layer "F.SilkS")
			(hide yes)
			(effects
				(font
					(size 1.27 1.27)
				)
			)
		)
		(property "Value" "4K7R2F-GP"
			(at 0.064008 -3.993896 180)
			(unlocked yes)
			(layer "F.Fab")
			(hide yes)
			(effects
				(font
					(size 1.016 1.016)
					(thickness 0.1524)
				)
			)
		)
		(property "Device Type" "R402H16"
			(at 0.064008 -5.517896 180)
			(unlocked yes)
			(layer "F.Fab")
			(hide yes)
			(effects
				(font
					(size 1.016 1.016)
					(thickness 0.1524)
				)
			)
		)
		(duplicate_pad_numbers_are_jumpers no)
		(fp_line
			(start 0.508 -0.9398)
			(end -0.508 -0.9398)
			(stroke
				(width 0.1524)
				(type default)
			)
			(layer "F.SilkS")
		)
		(fp_line
			(start -0.508 -0.9398)
			(end -0.508 0.9398)
			(stroke
				(width 0.1524)
				(type default)
			)
			(layer "F.SilkS")
		)
		(fp_rect
			(start -0.508 0.9398)
			(end 0.508 -0.9398)
			(stroke
				(width 0)
				(type default)
			)
			(fill no)
			(layer "F.CrtYd")
		)
		(fp_rect
			(start -0.508 0.9398)
			(end 0.508 -0.9398)
			(stroke
				(width 0)
				(type default)
			)
			(fill no)
			(layer "F.Fab")
		)
		(pad "1" smd custom
			(at 0 -0.4445 180)
			(size 0.1397 0.1397)
			(layers "F.Cu" "F.Mask" "F.Paste")
			(net "IO_EXP0_HDD_FAULT_A0")
			(options
				(clearance outline)
				(anchor circle)
			)
			(primitives
				(gr_poly
					(pts
						(arc
							(start -0.1778 -0.2794)
							(mid -0.249642 -0.249642)
							(end -0.2794 -0.1778)
						)
						(arc
							(start -0.2794 0.1778)
							(mid -0.249642 0.249642)
							(end -0.1778 0.2794)
						)
						(arc
							(start 0.1778 0.2794)
							(mid 0.249642 0.249642)
							(end 0.2794 0.1778)
						)
						(arc
							(start 0.2794 -0.1778)
							(mid 0.249642 -0.249642)
							(end 0.1778 -0.2794)
						)
					)
					(width 0)
					(fill yes)
				)
			)
		)
		(pad "2" smd custom
			(at 0 0.4445 180)
			(size 0.1397 0.1397)
			(layers "F.Cu" "F.Mask" "F.Paste")
			(net "GND")
			(options
				(clearance outline)
				(anchor circle)
			)
			(primitives
				(gr_poly
					(pts
						(arc
							(start -0.1778 -0.2794)
							(mid -0.249642 -0.249642)
							(end -0.2794 -0.1778)
						)
						(arc
							(start -0.2794 0.1778)
							(mid -0.249642 0.249642)
							(end -0.1778 0.2794)
						)
						(arc
							(start 0.1778 0.2794)
							(mid 0.249642 0.249642)
							(end 0.2794 0.1778)
						)
						(arc
							(start 0.2794 -0.1778)
							(mid 0.249642 -0.249642)
							(end 0.1778 -0.2794)
						)
					)
					(width 0)
					(fill yes)
				)
			)
		)
	)
	(footprint ""
		(layer "F.Cu")
		(at 117.646196 -46.014894 -90)
		(property "Reference" "R759"
			(at 0 0 270)
			(layer "F.SilkS")
			(hide yes)
			(effects
				(font
					(size 1.27 1.27)
				)
			)
		)
		(property "Value" "1KR2F-3-GP"
			(at 0.064008 -3.993896 270)
			(unlocked yes)
			(layer "F.Fab")
			(hide yes)
			(effects
				(font
					(size 1.016 1.016)
					(thickness 0.1524)
				)
			)
		)
		(property "Device Type" "R402H16"
			(at 0.064008 -5.517896 270)
			(unlocked yes)
			(layer "F.Fab")
			(hide yes)
			(effects
				(font
					(size 1.016 1.016)
					(thickness 0.1524)
				)
			)
		)
		(duplicate_pad_numbers_are_jumpers no)
		(fp_line
			(start -0.508 -0.9398)
			(end -0.508 0.9398)
			(stroke
				(width 0.1524)
				(type default)
			)
			(layer "F.SilkS")
		)
		(fp_line
			(start 0.508 -0.9398)
			(end -0.508 -0.9398)
			(stroke
				(width 0.1524)
				(type default)
			)
			(layer "F.SilkS")
		)
		(fp_rect
			(start -0.508 0.9398)
			(end 0.508 -0.9398)
			(stroke
				(width 0)
				(type default)
			)
			(fill no)
			(layer "F.CrtYd")
		)
		(fp_rect
			(start -0.508 0.9398)
			(end 0.508 -0.9398)
			(stroke
				(width 0)
				(type default)
			)
			(fill no)
			(layer "F.Fab")
		)
		(pad "1" smd custom
			(at 0 -0.4445 270)
			(size 0.1397 0.1397)
			(layers "F.Cu" "F.Mask" "F.Paste")
			(net "P3V3_STBY_A")
			(options
				(clearance outline)
				(anchor circle)
			)
			(primitives
				(gr_poly
					(pts
						(arc
							(start -0.1778 -0.2794)
							(mid -0.249642 -0.249642)
							(end -0.2794 -0.1778)
						)
						(arc
							(start -0.2794 0.1778)
							(mid -0.249642 0.249642)
							(end -0.1778 0.2794)
						)
						(arc
							(start 0.1778 0.2794)
							(mid 0.249642 0.249642)
							(end 0.2794 0.1778)
						)
						(arc
							(start 0.2794 -0.1778)
							(mid 0.249642 -0.249642)
							(end 0.1778 -0.2794)
						)
					)
					(width 0)
					(fill yes)
				)
			)
		)
		(pad "2" smd custom
			(at 0 0.4445 270)
			(size 0.1397 0.1397)
			(layers "F.Cu" "F.Mask" "F.Paste")
			(net "SW_PWR_R_HDD27")
			(options
				(clearance outline)
				(anchor circle)
			)
			(primitives
				(gr_poly
					(pts
						(arc
							(start -0.1778 -0.2794)
							(mid -0.249642 -0.249642)
							(end -0.2794 -0.1778)
						)
						(arc
							(start -0.2794 0.1778)
							(mid -0.249642 0.249642)
							(end -0.1778 0.2794)
						)
						(arc
							(start 0.1778 0.2794)
							(mid 0.249642 0.249642)
							(end 0.2794 0.1778)
						)
						(arc
							(start 0.2794 -0.1778)
							(mid 0.249642 -0.249642)
							(end 0.1778 -0.2794)
						)
					)
					(width 0)
					(fill yes)
				)
			)
		)
	)
	(footprint ""
		(layer "F.Cu")
		(at 14.715998 -179.683918 -90)
		(property "Reference" "C201"
			(at 0 0 270)
			(layer "F.SilkS")
			(hide yes)
			(effects
				(font
					(size 1.27 1.27)
				)
			)
		)
		(property "Value" "SC4D7U25V5KX-1-GP"
			(at -0.0762 -6.1214 270)
			(unlocked yes)
			(layer "F.Fab")
			(hide yes)
			(effects
				(font
					(size 1.016 1.016)
					(thickness 0.1524)
				)
			)
		)
		(property "Device Type" "C805H58"
			(at -0.0762 -8.1534 270)
			(unlocked yes)
			(layer "F.Fab")
			(hide yes)
			(effects
				(font
					(size 1.016 1.016)
					(thickness 0.1524)
				)
			)
		)
		(duplicate_pad_numbers_are_jumpers no)
		(fp_line
			(start 0.635 0)
			(end -0.635 0)
			(stroke
				(width 0.508)
				(type default)
			)
			(layer "F.SilkS")
		)
		(fp_rect
			(start -0.9652 1.778)
			(end 0.9652 -1.778)
			(stroke
				(width 0)
				(type default)
			)
			(fill no)
			(layer "F.CrtYd")
		)
		(fp_poly
			(pts
				(xy -0.9652 -1.778) (xy 0.9652 -1.778) (xy 0.9652 1.778) (xy -0.9652 1.778)
			)
			(stroke
				(width 0)
				(type default)
			)
			(fill no)
			(layer "F.Fab")
		)
		(pad "1" smd rect
			(at 0 -0.9652 270)
			(size 1.397 1.143)
			(layers "F.Cu" "F.Mask" "F.Paste")
			(net "P12V_HDD12")
		)
		(pad "2" smd rect
			(at 0 0.9652 270)
			(size 1.397 1.143)
			(layers "F.Cu" "F.Mask" "F.Paste")
			(net "GND")
		)
	)
)
